(kicad_pcb
	(version 20241229)
	(generator "pcbnew")
	(generator_version "9.0")
	(general
		(thickness 1.711)
		(legacy_teardrops no)
	)
	(paper "A4")
	(title_block
		(title "Antmicro Baseboard for Jetson AGX Thor")
		(date "2026-02-18")
		(rev "1.1.0")
		(company "Antmicro Ltd")
		(comment 1 "www.antmicro.com")
		(comment 9 "footprints 1145-1148 of 1170")
	)
	(layers
		(0 "F.Cu" signal)
		(4 "In1.Cu" signal)
		(6 "In2.Cu" signal)
		(8 "In3.Cu" signal)
		(10 "In4.Cu" jumper)
		(12 "In5.Cu" signal)
		(14 "In6.Cu" signal)
		(16 "In7.Cu" signal)
		(18 "In8.Cu" signal)
		(2 "B.Cu" signal)
		(9 "F.Adhes" user "F.Adhesive")
		(11 "B.Adhes" user "B.Adhesive")
		(13 "F.Paste" user)
		(15 "B.Paste" user)
		(5 "F.SilkS" user "F.Silkscreen")
		(7 "B.SilkS" user "B.Silkscreen")
		(1 "F.Mask" user)
		(3 "B.Mask" user)
		(17 "Dwgs.User" user "User.Drawings")
		(19 "Cmts.User" user "User.Comments")
		(21 "Eco1.User" user "User.Eco1")
		(23 "Eco2.User" user "User.Eco2")
		(25 "Edge.Cuts" user)
		(27 "Margin" user)
		(31 "F.CrtYd" user "F.Courtyard")
		(29 "B.CrtYd" user "B.Courtyard")
		(35 "F.Fab" user)
		(33 "B.Fab" user)
	)
	(footprint "antmicro-footprints:R_0402_1005Metric"
		(layer "B.Cu")
		(at 157.15 67.53 180)
		(descr "Resistor SMD 0402")
		(tags "resistor SMD 0402")
		(property "Reference" "R292"
			(at -1.07 -4.17 0)
			(layer "B.SilkS")
			(effects
				(font
					(size 0.7 0.7)
					(thickness 0.15)
				)
				(justify left bottom mirror)
			)
		)
		(property "Value" "R_0R_0402"
			(at -1.011843 -1.772047 0)
			(layer "B.Fab")
			(effects
				(font
					(size 0.7 0.7)
					(thickness 0.15)
				)
				(justify left bottom mirror)
			)
		)
		(property "Datasheet" "https://industrial.panasonic.com/cdbs/www-data/pdf/RDA0000/AOA0000C301.pdf"
			(at 0 0 0)
			(layer "B.Fab")
			(hide yes)
			(effects
				(font
					(size 1.27 1.27)
					(thickness 0.15)
				)
				(justify mirror)
			)
		)
		(property "Description" "SMD Chip Resistor, Jumper, 0 ohm, 100 mW, 0402 [1005 Metric], Thick Film, General Purpose"
			(at 0 0 0)
			(layer "B.Fab")
			(hide yes)
			(effects
				(font
					(size 1.27 1.27)
					(thickness 0.15)
				)
				(justify mirror)
			)
		)
		(property "MPN" "ERJ2GE0R00X"
			(at 0 0 0)
			(unlocked yes)
			(layer "B.Fab")
			(hide yes)
			(effects
				(font
					(size 1 1)
					(thickness 0.15)
				)
				(justify mirror)
			)
		)
		(property "Manufacturer" "Panasonic"
			(at 0 0 0)
			(unlocked yes)
			(layer "B.Fab")
			(hide yes)
			(effects
				(font
					(size 1 1)
					(thickness 0.15)
				)
				(justify mirror)
			)
		)
		(property "License" "Apache-2.0"
			(at 0 0 0)
			(unlocked yes)
			(layer "B.Fab")
			(hide yes)
			(effects
				(font
					(size 1 1)
					(thickness 0.15)
				)
				(justify mirror)
			)
		)
		(property "Author" "Antmicro"
			(at 0 0 0)
			(unlocked yes)
			(layer "B.Fab")
			(hide yes)
			(effects
				(font
					(size 1 1)
					(thickness 0.15)
				)
				(justify mirror)
			)
		)
		(property "Val" "0R"
			(at 0 0 0)
			(unlocked yes)
			(layer "B.Fab")
			(hide yes)
			(effects
				(font
					(size 1 1)
					(thickness 0.15)
				)
				(justify mirror)
			)
		)
		(property "Tolerance" "~"
			(at 0 0 0)
			(unlocked yes)
			(layer "B.Fab")
			(hide yes)
			(effects
				(font
					(size 1 1)
					(thickness 0.15)
				)
				(justify mirror)
			)
		)
		(property "Current" "1A"
			(at 0 0 0)
			(unlocked yes)
			(layer "B.Fab")
			(hide yes)
			(effects
				(font
					(size 1 1)
					(thickness 0.15)
				)
				(justify mirror)
			)
		)
		(sheetname "/SoM_IO2/")
		(sheetfile "som_io2.kicad_sch")
		(attr smd exclude_from_pos_files exclude_from_bom dnp)
		(fp_rect
			(start -0.925 0.47)
			(end 0.925 -0.47)
			(stroke
				(width 0.05)
				(type default)
			)
			(fill no)
			(layer "B.CrtYd")
		)
		(fp_rect
			(start -0.5 0.25)
			(end 0.5 -0.25)
			(stroke
				(width 0.15)
				(type solid)
			)
			(fill no)
			(layer "B.Fab")
		)
		(fp_text user "Author: Antmicro"
			(at -0.95 -4.169 0)
			(layer "B.Fab")
			(effects
				(font
					(size 0.7 0.7)
					(thickness 0.15)
				)
				(justify left bottom mirror)
			)
		)
		(fp_text user "${REFERENCE}"
			(at -0.95 -3.168 0)
			(layer "B.Fab")
			(effects
				(font
					(size 0.7 0.7)
					(thickness 0.15)
				)
				(justify left bottom mirror)
			)
		)
		(fp_text user "License: Apache-2.0"
			(at -0.95 -5.169 0)
			(layer "B.Fab")
			(effects
				(font
					(size 0.7 0.7)
					(thickness 0.15)
				)
				(justify left bottom mirror)
			)
		)
		(pad "1" smd roundrect
			(at -0.48 0 180)
			(size 0.59 0.64)
			(layers "B.Cu" "B.Mask" "B.Paste")
			(roundrect_rratio 0.25)
			(net 1028 "Net-(U59-B3Y)")
			(pintype "passive")
		)
		(pad "2" smd roundrect
			(at 0.48 0 180)
			(size 0.59 0.64)
			(layers "B.Cu" "B.Mask" "B.Paste")
			(roundrect_rratio 0.25)
			(net 743 "/SoM_IO2/JTAG_TCK")
			(pintype "passive")
		)
	)
	(footprint "antmicro-footprints:Fiducial_1mm_Mask3mm"
		(layer "B.Cu")
		(at 237.74 55.81 180)
		(descr "Circular Fiducial, 1.5mm bare copper, 3mm soldermask opening")
		(tags "fiducial")
		(property "Reference" "FD5"
			(at 1.57 -0.43 0)
			(layer "B.SilkS")
			(effects
				(font
					(size 0.7 0.7)
					(thickness 0.15)
				)
				(justify left bottom mirror)
			)
		)
		(property "Value" "Fiducial_1mm_Mask3mm"
			(at 0 -2.603 0)
			(layer "B.Fab")
			(effects
				(font
					(size 0.7 0.7)
					(thickness 0.15)
				)
				(justify left bottom mirror)
			)
		)
		(property "Description" "Fiducial mask"
			(at 0 0 0)
			(layer "B.Fab")
			(hide yes)
			(effects
				(font
					(size 1.27 1.27)
					(thickness 0.15)
				)
				(justify mirror)
			)
		)
		(property "Author" "Antmicro"
			(at 0 0 0)
			(unlocked yes)
			(layer "B.Fab")
			(hide yes)
			(effects
				(font
					(size 1 1)
					(thickness 0.15)
				)
				(justify mirror)
			)
		)
		(property "License" "Apache-2.0"
			(at 0 0 0)
			(unlocked yes)
			(layer "B.Fab")
			(hide yes)
			(effects
				(font
					(size 1 1)
					(thickness 0.15)
				)
				(justify mirror)
			)
		)
		(sheetname "/")
		(sheetfile "jetson-agx-thor-baseboard.kicad_sch")
		(attr exclude_from_pos_files exclude_from_bom)
		(fp_circle
			(center 0 0)
			(end 1.5 0)
			(stroke
				(width 0.05)
				(type solid)
			)
			(fill no)
			(layer "B.CrtYd")
		)
		(fp_circle
			(center 0 0)
			(end 1.5 0)
			(stroke
				(width 0.15)
				(type solid)
			)
			(fill no)
			(layer "B.Fab")
		)
		(fp_text user "${REFERENCE}"
			(at -1.25 -4.603 0)
			(layer "B.Fab")
			(effects
				(font
					(size 0.7 0.7)
					(thickness 0.15)
				)
				(justify left bottom mirror)
			)
		)
		(fp_text user "License: Apache-2.0"
			(at -1.25 -7.003 0)
			(layer "B.Fab")
			(effects
				(font
					(size 0.7 0.7)
					(thickness 0.15)
				)
				(justify left bottom mirror)
			)
		)
		(fp_text user "Author: Antmicro"
			(at -1.25 -5.803 0)
			(layer "B.Fab")
			(effects
				(font
					(size 0.7 0.7)
					(thickness 0.15)
				)
				(justify left bottom mirror)
			)
		)
		(pad "" smd circle
			(at 0 0 180)
			(size 1 1)
			(layers "B.Cu" "B.Mask")
			(solder_mask_margin 1)
			(clearance 1)
		)
	)
	(footprint "antmicro-footprints:R_0402_1005Metric"
		(layer "B.Cu")
		(at 175.568 60.063002 90)
		(descr "Resistor SMD 0402")
		(tags "resistor SMD 0402")
		(property "Reference" "R229"
			(at -1.536998 0.632 90)
			(layer "B.SilkS")
			(effects
				(font
					(size 0.7 0.7)
					(thickness 0.15)
				)
				(justify right top mirror)
			)
		)
		(property "Value" "R_100k_0402"
			(at -1.011843 -1.772047 90)
			(layer "B.Fab")
			(effects
				(font
					(size 0.7 0.7)
					(thickness 0.15)
				)
				(justify right top mirror)
			)
		)
		(property "Datasheet" "https://www.bourns.com/docs/product-datasheets/cr.pdf"
			(at 0 0 90)
			(layer "B.Fab")
			(hide yes)
			(effects
				(font
					(size 1.27 1.27)
					(thickness 0.15)
				)
				(justify mirror)
			)
		)
		(property "Description" "SMD Chip Resistor, 100 kohm, ± 1%, 62.5 mW, 0402 [1005 Metric], Thick Film, General Purpose"
			(at 0 0 90)
			(layer "B.Fab")
			(hide yes)
			(effects
				(font
					(size 1.27 1.27)
					(thickness 0.15)
				)
				(justify mirror)
			)
		)
		(property "Manufacturer" "Bourns"
			(at 0 0 270)
			(unlocked yes)
			(layer "B.Fab")
			(hide yes)
			(effects
				(font
					(size 1 1)
					(thickness 0.15)
				)
				(justify mirror)
			)
		)
		(property "MPN" "CR0402-FX-1003GLF"
			(at 0 0 270)
			(unlocked yes)
			(layer "B.Fab")
			(hide yes)
			(effects
				(font
					(size 1 1)
					(thickness 0.15)
				)
				(justify mirror)
			)
		)
		(property "Val" "100k"
			(at 0 0 270)
			(unlocked yes)
			(layer "B.Fab")
			(hide yes)
			(effects
				(font
					(size 1 1)
					(thickness 0.15)
				)
				(justify mirror)
			)
		)
		(property "License" "Apache-2.0"
			(at 0 0 270)
			(unlocked yes)
			(layer "B.Fab")
			(hide yes)
			(effects
				(font
					(size 1 1)
					(thickness 0.15)
				)
				(justify mirror)
			)
		)
		(property "Author" "Antmicro"
			(at 0 0 270)
			(unlocked yes)
			(layer "B.Fab")
			(hide yes)
			(effects
				(font
					(size 1 1)
					(thickness 0.15)
				)
				(justify mirror)
			)
		)
		(property "Tolerance" "1%"
			(at 0 0 270)
			(unlocked yes)
			(layer "B.Fab")
			(hide yes)
			(effects
				(font
					(size 1 1)
					(thickness 0.15)
				)
				(justify mirror)
			)
		)
		(sheetname "/Peripherals/")
		(sheetfile "peripherals.kicad_sch")
		(attr smd)
		(fp_rect
			(start -0.925 0.47)
			(end 0.925 -0.47)
			(stroke
				(width 0.05)
				(type default)
			)
			(fill no)
			(layer "B.CrtYd")
		)
		(fp_rect
			(start -0.5 0.25)
			(end 0.5 -0.25)
			(stroke
				(width 0.15)
				(type solid)
			)
			(fill no)
			(layer "B.Fab")
		)
		(fp_text user "License: Apache-2.0"
			(at -0.95 -5.169 90)
			(layer "B.Fab")
			(effects
				(font
					(size 0.7 0.7)
					(thickness 0.15)
				)
				(justify right top mirror)
			)
		)
		(fp_text user "Author: Antmicro"
			(at -0.95 -4.169 90)
			(layer "B.Fab")
			(effects
				(font
					(size 0.7 0.7)
					(thickness 0.15)
				)
				(justify right top mirror)
			)
		)
		(fp_text user "${REFERENCE}"
			(at -0.95 -3.168 90)
			(layer "B.Fab")
			(effects
				(font
					(size 0.7 0.7)
					(thickness 0.15)
				)
				(justify right top mirror)
			)
		)
		(pad "1" smd roundrect
			(at -0.48 0 90)
			(size 0.59 0.64)
			(layers "B.Cu" "B.Mask" "B.Paste")
			(roundrect_rratio 0.25)
			(net 1 "GND")
			(pintype "passive")
		)
		(pad "2" smd roundrect
			(at 0.48 0 90)
			(size 0.59 0.64)
			(layers "B.Cu" "B.Mask" "B.Paste")
			(roundrect_rratio 0.25)
			(net 487 "/Expansion connector/GPIO.USER_LED0")
			(pintype "passive")
		)
	)
	(footprint "antmicro-footprints:C_0402_1005Metric"
		(layer "B.Cu")
		(at 110.25 101.5)
		(descr "Capacitor SMD 0402")
		(tags "capacitor SMD 0402")
		(property "Reference" "C187"
			(at -0.95 -0.301 0)
			(layer "B.SilkS")
			(effects
				(font
					(size 0.7 0.7)
					(thickness 0.15)
				)
				(justify left top mirror)
			)
		)
		(property "Value" "C_220n_0402"
			(at -1.022927 -2.155213 0)
			(layer "B.Fab")
			(effects
				(font
					(size 0.7 0.7)
					(thickness 0.15)
				)
				(justify right top mirror)
			)
		)
		(property "Datasheet" "https://www.yageo.com/en/Chart/Download/pdf/CC0402KRX5R6BB224"
			(at 0 0 0)
			(layer "B.Fab")
			(hide yes)
			(effects
				(font
					(size 1.27 1.27)
					(thickness 0.15)
				)
				(justify mirror)
			)
		)
		(property "Description" "SMD Multilayer Ceramic Capacitor, 0.22 µF, 10 V, 0402 [1005 Metric], ± 10%, X5R, CC Series"
			(at 0 0 0)
			(layer "B.Fab")
			(hide yes)
			(effects
				(font
					(size 1.27 1.27)
					(thickness 0.15)
				)
				(justify mirror)
			)
		)
		(property "MPN" "CC0402KRX5R6BB224"
			(at 0 0 0)
			(unlocked yes)
			(layer "B.Fab")
			(hide yes)
			(effects
				(font
					(size 1 1)
					(thickness 0.15)
				)
				(justify mirror)
			)
		)
		(property "Val" "220n"
			(at 0 0 0)
			(unlocked yes)
			(layer "B.Fab")
			(hide yes)
			(effects
				(font
					(size 1 1)
					(thickness 0.15)
				)
				(justify mirror)
			)
		)
		(property "Voltage" "25V"
			(at 0 0 0)
			(unlocked yes)
			(layer "B.Fab")
			(hide yes)
			(effects
				(font
					(size 1 1)
					(thickness 0.15)
				)
				(justify mirror)
			)
		)
		(property "Dielectric" "X7R"
			(at 0 0 0)
			(unlocked yes)
			(layer "B.Fab")
			(hide yes)
			(effects
				(font
					(size 1 1)
					(thickness 0.15)
				)
				(justify mirror)
			)
		)
		(property "Manufacturer" "YAGEO"
			(at 0 0 0)
			(unlocked yes)
			(layer "B.Fab")
			(hide yes)
			(effects
				(font
					(size 1 1)
					(thickness 0.15)
				)
				(justify mirror)
			)
		)
		(property "License" "Apache-2.0"
			(at 0 0 0)
			(unlocked yes)
			(layer "B.Fab")
			(hide yes)
			(effects
				(font
					(size 1 1)
					(thickness 0.15)
				)
				(justify mirror)
			)
		)
		(property "Author" "Antmicro"
			(at 0 0 0)
			(unlocked yes)
			(layer "B.Fab")
			(hide yes)
			(effects
				(font
					(size 1 1)
					(thickness 0.15)
				)
				(justify mirror)
			)
		)
		(property "Public" "False"
			(at 0 0 0)
			(unlocked yes)
			(layer "B.Fab")
			(hide yes)
			(effects
				(font
					(size 1 1)
					(thickness 0.15)
				)
				(justify mirror)
			)
		)
		(sheetname "/M.2/")
		(sheetfile "m2.kicad_sch")
		(attr smd)
		(fp_poly
			(pts
				(xy -0.925 0.47) (xy -0.925 -0.47) (xy 0.925 -0.47) (xy 0.925 0.47)
			)
			(stroke
				(width 0.05)
				(type default)
			)
			(fill no)
			(layer "B.CrtYd")
		)
		(fp_line
			(start -0.494 -0.248)
			(end -0.494 0.25)
			(stroke
				(width 0.15)
				(type solid)
			)
			(layer "B.Fab")
		)
		(fp_line
			(start -0.494 0.25)
			(end 0.504 0.25)
			(stroke
				(width 0.15)
				(type solid)
			)
			(layer "B.Fab")
		)
		(fp_line
			(start 0.504 -0.248)
			(end -0.494 -0.248)
			(stroke
				(width 0.15)
				(type solid)
			)
			(layer "B.Fab")
		)
		(fp_line
			(start 0.504 0.25)
			(end 0.504 -0.248)
			(stroke
				(width 0.15)
				(type solid)
			)
			(layer "B.Fab")
		)
		(fp_text user "License: Apache-2.0"
			(at -0.939 -5.799 0)
			(layer "B.Fab")
			(effects
				(font
					(size 0.7 0.7)
					(thickness 0.15)
				)
				(justify right top mirror)
			)
		)
		(fp_text user "${REFERENCE}"
			(at -0.939 -4.599 0)
			(layer "B.Fab")
			(effects
				(font
					(size 0.7 0.7)
					(thickness 0.15)
				)
				(justify right top mirror)
			)
		)
		(fp_text user "Author: Antmicro"
			(at -0.939 -3.399 0)
			(layer "B.Fab")
			(effects
				(font
					(size 0.7 0.7)
					(thickness 0.15)
				)
				(justify right top mirror)
			)
		)
		(pad "1" smd roundrect
			(at -0.48 0)
			(size 0.59 0.64)
			(layers "B.Cu" "B.Mask" "B.Paste")
			(roundrect_rratio 0.25)
			(net 435 "/M.2/PCIe_{C5x4}.TX2-")
			(pintype "passive")
		)
		(pad "2" smd roundrect
			(at 0.48 0)
			(size 0.59 0.64)
			(layers "B.Cu" "B.Mask" "B.Paste")
			(roundrect_rratio 0.25)
			(net 423 "/M.2/M2_M_PET2_N")
			(pintype "passive")
		)
	)
)
